(kicad_pcb
	(version 20241229)
	(generator "pcbnew")
	(generator_version "9.0")
	(general
		(thickness 1.599998)
		(legacy_teardrops no)
	)
	(paper "A4")
	(title_block
		(title "Artix - Datacenter Secure Control Module (DC-SCM)")
		(date "2024-11-06")
		(rev "1.1.3")
		(comment 9 "footprints 430-435 of 544")
	)
	(layers
		(0 "F.Cu" signal)
		(4 "In1.Cu" signal)
		(6 "In2.Cu" signal)
		(8 "In3.Cu" signal)
		(10 "In4.Cu" signal)
		(12 "In5.Cu" signal)
		(14 "In6.Cu" signal)
		(2 "B.Cu" signal)
		(9 "F.Adhes" user "F.Adhesive")
		(11 "B.Adhes" user "B.Adhesive")
		(13 "F.Paste" user)
		(15 "B.Paste" user)
		(5 "F.SilkS" user "F.Silkscreen")
		(7 "B.SilkS" user "B.Silkscreen")
		(1 "F.Mask" user)
		(3 "B.Mask" user)
		(17 "Dwgs.User" user "User.Drawings")
		(19 "Cmts.User" user "User.Comments")
		(21 "Eco1.User" user "User.Eco1")
		(23 "Eco2.User" user "User.Eco2")
		(25 "Edge.Cuts" user)
		(27 "Margin" user)
		(31 "F.CrtYd" user "F.Courtyard")
		(29 "B.CrtYd" user "B.Courtyard")
		(35 "F.Fab" user)
		(33 "B.Fab" user)
	)
	(footprint "antmicro-footprints:C_0603_1608Metric"
		(layer "B.Cu")
		(at 118.6 126.4 -90)
		(descr "Capacitor SMD 0603")
		(tags "capacitor 0603")
		(property "Reference" "C45"
			(at -1.1 0.6 90)
			(layer "B.SilkS")
			(effects
				(font
					(size 0.7 0.7)
					(thickness 0.15)
				)
				(justify left bottom mirror)
			)
		)
		(property "Value" "C_4u7_0603"
			(at 0 -1.6 90)
			(layer "B.Fab")
			(effects
				(font
					(size 0.7 0.7)
					(thickness 0.15)
				)
				(justify left bottom mirror)
			)
		)
		(property "Datasheet" "https://product.tdk.com/en/search/capacitor/ceramic/mlcc/info?part_no=C1608X5R1V475M080AC"
			(at 0 0 270)
			(layer "F.Fab")
			(hide yes)
			(effects
				(font
					(size 1.27 1.27)
					(thickness 0.15)
				)
			)
		)
		(property "Description" "SMD Multilayer Ceramic Capacitor, 4.7 µF, 35 V, 0603 [1608 Metric], ± 20%, X5R, C"
			(at 0 0 270)
			(layer "F.Fab")
			(hide yes)
			(effects
				(font
					(size 1.27 1.27)
					(thickness 0.15)
				)
			)
		)
		(property "Author" "Antmicro"
			(at -7.8 245 0)
			(layer "B.Fab")
			(hide yes)
			(effects
				(font
					(size 1 1)
					(thickness 0.15)
				)
				(justify mirror)
			)
		)
		(property "Dielectric" ""
			(at -7.8 245 0)
			(layer "B.Fab")
			(hide yes)
			(effects
				(font
					(size 1 1)
					(thickness 0.15)
				)
				(justify mirror)
			)
		)
		(property "License" "Apache-2.0"
			(at -7.8 245 0)
			(layer "B.Fab")
			(hide yes)
			(effects
				(font
					(size 1 1)
					(thickness 0.15)
				)
				(justify mirror)
			)
		)
		(property "MPN" "C1608X5R1V475M080AC"
			(at -7.8 245 0)
			(layer "B.Fab")
			(hide yes)
			(effects
				(font
					(size 1 1)
					(thickness 0.15)
				)
				(justify mirror)
			)
		)
		(property "Manufacturer" "TDK"
			(at -7.8 245 0)
			(layer "B.Fab")
			(hide yes)
			(effects
				(font
					(size 1 1)
					(thickness 0.15)
				)
				(justify mirror)
			)
		)
		(property "Val" "4u7"
			(at -7.8 245 0)
			(layer "B.Fab")
			(hide yes)
			(effects
				(font
					(size 1 1)
					(thickness 0.15)
				)
				(justify mirror)
			)
		)
		(property "Voltage" ""
			(at -7.8 245 0)
			(layer "B.Fab")
			(hide yes)
			(effects
				(font
					(size 1 1)
					(thickness 0.15)
				)
				(justify mirror)
			)
		)
		(sheetname "/Interfaces/")
		(sheetfile "interfaces.kicad_sch")
		(attr smd)
		(fp_line
			(start -0.15 0.4)
			(end 0.15 0.4)
			(stroke
				(width 0.15)
				(type solid)
			)
			(layer "B.SilkS")
		)
		(fp_line
			(start -0.15 -0.4)
			(end 0.15 -0.4)
			(stroke
				(width 0.15)
				(type solid)
			)
			(layer "B.SilkS")
		)
		(fp_rect
			(start -1.25 0.65)
			(end 1.25 -0.65)
			(stroke
				(width 0.05)
				(type solid)
			)
			(fill no)
			(layer "B.CrtYd")
		)
		(fp_rect
			(start -0.8 0.4)
			(end 0.8 -0.4)
			(stroke
				(width 0.15)
				(type solid)
			)
			(fill no)
			(layer "B.Fab")
		)
		(pad "1" smd roundrect
			(at -0.7 0 270)
			(size 0.8 1)
			(layers "B.Cu" "B.Mask" "B.Paste")
			(roundrect_rratio 0.2)
			(net 1 "GND")
			(pintype "passive")
		)
		(pad "2" smd roundrect
			(at 0.7 0 270)
			(size 0.8 1)
			(layers "B.Cu" "B.Mask" "B.Paste")
			(roundrect_rratio 0.2)
			(net 339 "VCC1V2")
			(pintype "passive")
		)
	)
	(footprint "antmicro-footprints:R_0402_1005Metric"
		(layer "B.Cu")
		(at 107.719 92.077 180)
		(descr "Resistor SMD 0402")
		(tags "resistor SMD 0402")
		(property "Reference" "R159"
			(at -5.881 2.277 0)
			(layer "B.SilkS")
			(effects
				(font
					(size 0.7 0.7)
					(thickness 0.15)
				)
				(justify left bottom mirror)
			)
		)
		(property "Value" "R_12k1_0402"
			(at 0 -1.4 0)
			(layer "B.Fab")
			(effects
				(font
					(size 0.7 0.7)
					(thickness 0.15)
				)
				(justify left bottom mirror)
			)
		)
		(property "Datasheet" "https://www.bourns.com/docs/product-datasheets/cr.pdf"
			(at 0 0 180)
			(layer "F.Fab")
			(hide yes)
			(effects
				(font
					(size 1.27 1.27)
					(thickness 0.15)
				)
			)
		)
		(property "Description" "SMD Chip Resistor, 12.1 kohm, ± 1%, 62.5 mW, 0402 [1005 Metric], Thick Film, General Purpose"
			(at 0 0 180)
			(layer "F.Fab")
			(hide yes)
			(effects
				(font
					(size 1.27 1.27)
					(thickness 0.15)
				)
			)
		)
		(property "Author" "Antmicro"
			(at 215.438 184.154 0)
			(layer "B.Fab")
			(hide yes)
			(effects
				(font
					(size 1 1)
					(thickness 0.15)
				)
				(justify mirror)
			)
		)
		(property "License" "Apache-2.0"
			(at 215.438 184.154 0)
			(layer "B.Fab")
			(hide yes)
			(effects
				(font
					(size 1 1)
					(thickness 0.15)
				)
				(justify mirror)
			)
		)
		(property "MPN" "CR0402-FX-1212GLF"
			(at 215.438 184.154 0)
			(layer "B.Fab")
			(hide yes)
			(effects
				(font
					(size 1 1)
					(thickness 0.15)
				)
				(justify mirror)
			)
		)
		(property "Manufacturer" "Bourns"
			(at 215.438 184.154 0)
			(layer "B.Fab")
			(hide yes)
			(effects
				(font
					(size 1 1)
					(thickness 0.15)
				)
				(justify mirror)
			)
		)
		(property "Tolerance" "1%"
			(at 215.438 184.154 0)
			(layer "B.Fab")
			(hide yes)
			(effects
				(font
					(size 1 1)
					(thickness 0.15)
				)
				(justify mirror)
			)
		)
		(property "Val" "12k1"
			(at 215.438 184.154 0)
			(layer "B.Fab")
			(hide yes)
			(effects
				(font
					(size 1 1)
					(thickness 0.15)
				)
				(justify mirror)
			)
		)
		(sheetname "/Ethernet/")
		(sheetfile "ethernet.kicad_sch")
		(attr smd)
		(fp_rect
			(start -0.925 0.47)
			(end 0.925 -0.47)
			(stroke
				(width 0.05)
				(type default)
			)
			(fill no)
			(layer "B.CrtYd")
		)
		(fp_rect
			(start -0.5 0.25)
			(end 0.5 -0.25)
			(stroke
				(width 0.15)
				(type solid)
			)
			(fill no)
			(layer "B.Fab")
		)
		(pad "1" smd roundrect
			(at -0.48 0 180)
			(size 0.59 0.64)
			(layers "B.Cu" "B.Mask" "B.Paste")
			(roundrect_rratio 0.25)
			(net 1 "GND")
			(pintype "passive")
		)
		(pad "2" smd roundrect
			(at 0.48 0 180)
			(size 0.59 0.64)
			(layers "B.Cu" "B.Mask" "B.Paste")
			(roundrect_rratio 0.25)
			(net 345 "Net-(U20-ISET)")
			(pintype "passive")
		)
	)
	(footprint "antmicro-footprints:C_0402_1005Metric"
		(layer "B.Cu")
		(at 140.274 130.314 180)
		(descr "Capacitor SMD 0402")
		(tags "capacitor SMD 0402")
		(property "Reference" "C188"
			(at -3.626 -0.386 0)
			(layer "B.SilkS")
			(effects
				(font
					(size 0.7 0.7)
					(thickness 0.15)
				)
				(justify left bottom mirror)
			)
		)
		(property "Value" "C_4u7_0402"
			(at 0 -1.4 0)
			(layer "B.Fab")
			(effects
				(font
					(size 0.7 0.7)
					(thickness 0.15)
				)
				(justify left bottom mirror)
			)
		)
		(property "Datasheet" "https://www.murata.com/products/productdetail?partno=GRM155R61A475MEAA%23"
			(at 0 0 180)
			(layer "F.Fab")
			(hide yes)
			(effects
				(font
					(size 1.27 1.27)
					(thickness 0.15)
				)
			)
		)
		(property "Description" "SMD Multilayer Ceramic Capacitor, 4.7 µF, 10 V, 0402 [1005 Metric], ± 20%, X5R, GRM Series"
			(at 0 0 180)
			(layer "F.Fab")
			(hide yes)
			(effects
				(font
					(size 1.27 1.27)
					(thickness 0.15)
				)
			)
		)
		(property "Author" "Antmicro"
			(at 280.548 260.628 0)
			(layer "B.Fab")
			(hide yes)
			(effects
				(font
					(size 1 1)
					(thickness 0.15)
				)
				(justify mirror)
			)
		)
		(property "Dielectric" ""
			(at 280.548 260.628 0)
			(layer "B.Fab")
			(hide yes)
			(effects
				(font
					(size 1 1)
					(thickness 0.15)
				)
				(justify mirror)
			)
		)
		(property "License" "Apache-2.0"
			(at 280.548 260.628 0)
			(layer "B.Fab")
			(hide yes)
			(effects
				(font
					(size 1 1)
					(thickness 0.15)
				)
				(justify mirror)
			)
		)
		(property "MPN" "GRM155R61A475MEAAD"
			(at 280.548 260.628 0)
			(layer "B.Fab")
			(hide yes)
			(effects
				(font
					(size 1 1)
					(thickness 0.15)
				)
				(justify mirror)
			)
		)
		(property "Manufacturer" "Murata"
			(at 280.548 260.628 0)
			(layer "B.Fab")
			(hide yes)
			(effects
				(font
					(size 1 1)
					(thickness 0.15)
				)
				(justify mirror)
			)
		)
		(property "Val" "4u7"
			(at 280.548 260.628 0)
			(layer "B.Fab")
			(hide yes)
			(effects
				(font
					(size 1 1)
					(thickness 0.15)
				)
				(justify mirror)
			)
		)
		(property "Voltage" ""
			(at 280.548 260.628 0)
			(layer "B.Fab")
			(hide yes)
			(effects
				(font
					(size 1 1)
					(thickness 0.15)
				)
				(justify mirror)
			)
		)
		(sheetname "/Interfaces/")
		(sheetfile "interfaces.kicad_sch")
		(attr smd)
		(fp_rect
			(start -0.925 0.47)
			(end 0.925 -0.47)
			(stroke
				(width 0.05)
				(type default)
			)
			(fill no)
			(layer "B.CrtYd")
		)
		(fp_line
			(start 0.504 0.25)
			(end 0.504 -0.248)
			(stroke
				(width 0.15)
				(type solid)
			)
			(layer "B.Fab")
		)
		(fp_line
			(start 0.504 -0.248)
			(end -0.494 -0.248)
			(stroke
				(width 0.15)
				(type solid)
			)
			(layer "B.Fab")
		)
		(fp_line
			(start -0.494 0.25)
			(end 0.504 0.25)
			(stroke
				(width 0.15)
				(type solid)
			)
			(layer "B.Fab")
		)
		(fp_line
			(start -0.494 -0.248)
			(end -0.494 0.25)
			(stroke
				(width 0.15)
				(type solid)
			)
			(layer "B.Fab")
		)
		(pad "1" smd roundrect
			(at -0.48 0 180)
			(size 0.59 0.64)
			(layers "B.Cu" "B.Mask" "B.Paste")
			(roundrect_rratio 0.25)
			(net 1 "GND")
			(pintype "passive")
		)
		(pad "2" smd roundrect
			(at 0.48 0 180)
			(size 0.59 0.64)
			(layers "B.Cu" "B.Mask" "B.Paste")
			(roundrect_rratio 0.25)
			(net 200 "Net-(U1-VDDIM)")
			(pintype "passive")
		)
	)
	(footprint "antmicro-footprints:R_0402_1005Metric"
		(layer "B.Cu")
		(at 138.774 122.004)
		(descr "Resistor SMD 0402")
		(tags "resistor SMD 0402")
		(property "Reference" "R117"
			(at -3.574 0.296 0)
			(layer "B.SilkS")
			(effects
				(font
					(size 0.7 0.7)
					(thickness 0.15)
				)
				(justify right bottom mirror)
			)
		)
		(property "Value" "R_47k_0402"
			(at 0 -1.4 0)
			(layer "B.Fab")
			(effects
				(font
					(size 0.7 0.7)
					(thickness 0.15)
				)
				(justify right bottom mirror)
			)
		)
		(property "Datasheet" "https://www.bourns.com/docs/product-datasheets/cr.pdf"
			(at 0 0 0)
			(layer "F.Fab")
			(hide yes)
			(effects
				(font
					(size 1.27 1.27)
					(thickness 0.15)
				)
			)
		)
		(property "Description" "SMD Chip Resistor, 47 kohm, ± 1%, 62.5 mW, 0402 [1005 Metric], Thick Film, General Purpose"
			(at 0 0 0)
			(layer "F.Fab")
			(hide yes)
			(effects
				(font
					(size 1.27 1.27)
					(thickness 0.15)
				)
			)
		)
		(property "Author" "Antmicro"
			(at 0 0 0)
			(layer "B.Fab")
			(hide yes)
			(effects
				(font
					(size 1 1)
					(thickness 0.15)
				)
				(justify mirror)
			)
		)
		(property "License" "Apache-2.0"
			(at 0 0 0)
			(layer "B.Fab")
			(hide yes)
			(effects
				(font
					(size 1 1)
					(thickness 0.15)
				)
				(justify mirror)
			)
		)
		(property "MPN" "CR0402-FX-4702GLF"
			(at 0 0 0)
			(layer "B.Fab")
			(hide yes)
			(effects
				(font
					(size 1 1)
					(thickness 0.15)
				)
				(justify mirror)
			)
		)
		(property "Manufacturer" "Bourns"
			(at 0 0 0)
			(layer "B.Fab")
			(hide yes)
			(effects
				(font
					(size 1 1)
					(thickness 0.15)
				)
				(justify mirror)
			)
		)
		(property "Tolerance" "1%"
			(at 0 0 0)
			(layer "B.Fab")
			(hide yes)
			(effects
				(font
					(size 1 1)
					(thickness 0.15)
				)
				(justify mirror)
			)
		)
		(property "Val" "47k"
			(at 0 0 0)
			(layer "B.Fab")
			(hide yes)
			(effects
				(font
					(size 1 1)
					(thickness 0.15)
				)
				(justify mirror)
			)
		)
		(sheetname "/Interfaces/")
		(sheetfile "interfaces.kicad_sch")
		(attr smd)
		(fp_rect
			(start -0.925 0.47)
			(end 0.925 -0.47)
			(stroke
				(width 0.05)
				(type default)
			)
			(fill no)
			(layer "B.CrtYd")
		)
		(fp_rect
			(start -0.5 0.25)
			(end 0.5 -0.25)
			(stroke
				(width 0.15)
				(type solid)
			)
			(fill no)
			(layer "B.Fab")
		)
		(pad "1" smd roundrect
			(at -0.48 0)
			(size 0.59 0.64)
			(layers "B.Cu" "B.Mask" "B.Paste")
			(roundrect_rratio 0.25)
			(net 2 "VCC3V3")
			(pintype "passive")
		)
		(pad "2" smd roundrect
			(at 0.48 0)
			(size 0.59 0.64)
			(layers "B.Cu" "B.Mask" "B.Paste")
			(roundrect_rratio 0.25)
			(net 331 "MMC_RSTN")
			(pintype "passive")
		)
	)
	(footprint "antmicro-footprints:R_0402_1005Metric"
		(layer "B.Cu")
		(at 139.764 120.004 180)
		(descr "Resistor SMD 0402")
		(tags "resistor SMD 0402")
		(property "Reference" "R118"
			(at -1.736 0.604 0)
			(layer "B.SilkS")
			(effects
				(font
					(size 0.7 0.7)
					(thickness 0.15)
				)
				(justify left bottom mirror)
			)
		)
		(property "Value" "R_47k_0402"
			(at 0 -1.4 0)
			(layer "B.Fab")
			(effects
				(font
					(size 0.7 0.7)
					(thickness 0.15)
				)
				(justify left bottom mirror)
			)
		)
		(property "Datasheet" "https://www.bourns.com/docs/product-datasheets/cr.pdf"
			(at 0 0 180)
			(layer "F.Fab")
			(hide yes)
			(effects
				(font
					(size 1.27 1.27)
					(thickness 0.15)
				)
			)
		)
		(property "Description" "SMD Chip Resistor, 47 kohm, ± 1%, 62.5 mW, 0402 [1005 Metric], Thick Film, General Purpose"
			(at 0 0 180)
			(layer "F.Fab")
			(hide yes)
			(effects
				(font
					(size 1.27 1.27)
					(thickness 0.15)
				)
			)
		)
		(property "Author" "Antmicro"
			(at 279.528 240.008 0)
			(layer "B.Fab")
			(hide yes)
			(effects
				(font
					(size 1 1)
					(thickness 0.15)
				)
				(justify mirror)
			)
		)
		(property "License" "Apache-2.0"
			(at 279.528 240.008 0)
			(layer "B.Fab")
			(hide yes)
			(effects
				(font
					(size 1 1)
					(thickness 0.15)
				)
				(justify mirror)
			)
		)
		(property "MPN" "CR0402-FX-4702GLF"
			(at 279.528 240.008 0)
			(layer "B.Fab")
			(hide yes)
			(effects
				(font
					(size 1 1)
					(thickness 0.15)
				)
				(justify mirror)
			)
		)
		(property "Manufacturer" "Bourns"
			(at 279.528 240.008 0)
			(layer "B.Fab")
			(hide yes)
			(effects
				(font
					(size 1 1)
					(thickness 0.15)
				)
				(justify mirror)
			)
		)
		(property "Tolerance" "1%"
			(at 279.528 240.008 0)
			(layer "B.Fab")
			(hide yes)
			(effects
				(font
					(size 1 1)
					(thickness 0.15)
				)
				(justify mirror)
			)
		)
		(property "Val" "47k"
			(at 279.528 240.008 0)
			(layer "B.Fab")
			(hide yes)
			(effects
				(font
					(size 1 1)
					(thickness 0.15)
				)
				(justify mirror)
			)
		)
		(sheetname "/Interfaces/")
		(sheetfile "interfaces.kicad_sch")
		(attr smd)
		(fp_rect
			(start -0.925 0.47)
			(end 0.925 -0.47)
			(stroke
				(width 0.05)
				(type default)
			)
			(fill no)
			(layer "B.CrtYd")
		)
		(fp_rect
			(start -0.5 0.25)
			(end 0.5 -0.25)
			(stroke
				(width 0.15)
				(type solid)
			)
			(fill no)
			(layer "B.Fab")
		)
		(pad "1" smd roundrect
			(at -0.48 0 180)
			(size 0.59 0.64)
			(layers "B.Cu" "B.Mask" "B.Paste")
			(roundrect_rratio 0.25)
			(net 2 "VCC3V3")
			(pintype "passive")
		)
		(pad "2" smd roundrect
			(at 0.48 0 180)
			(size 0.59 0.64)
			(layers "B.Cu" "B.Mask" "B.Paste")
			(roundrect_rratio 0.25)
			(net 329 "MMC_CMD")
			(pintype "passive")
		)
	)
	(footprint "antmicro-footprints:R_0402_1005Metric"
		(layer "B.Cu")
		(at 142.274 124.214 180)
		(descr "Resistor SMD 0402")
		(tags "resistor SMD 0402")
		(property "Reference" "R119"
			(at -3.626 -0.386 0)
			(layer "B.SilkS")
			(effects
				(font
					(size 0.7 0.7)
					(thickness 0.15)
				)
				(justify left bottom mirror)
			)
		)
		(property "Value" "R_47k_0402"
			(at 0 -1.4 0)
			(layer "B.Fab")
			(effects
				(font
					(size 0.7 0.7)
					(thickness 0.15)
				)
				(justify left bottom mirror)
			)
		)
		(property "Datasheet" "https://www.bourns.com/docs/product-datasheets/cr.pdf"
			(at 0 0 180)
			(layer "F.Fab")
			(hide yes)
			(effects
				(font
					(size 1.27 1.27)
					(thickness 0.15)
				)
			)
		)
		(property "Description" "SMD Chip Resistor, 47 kohm, ± 1%, 62.5 mW, 0402 [1005 Metric], Thick Film, General Purpose"
			(at 0 0 180)
			(layer "F.Fab")
			(hide yes)
			(effects
				(font
					(size 1.27 1.27)
					(thickness 0.15)
				)
			)
		)
		(property "Author" "Antmicro"
			(at 284.548 248.428 0)
			(layer "B.Fab")
			(hide yes)
			(effects
				(font
					(size 1 1)
					(thickness 0.15)
				)
				(justify mirror)
			)
		)
		(property "License" "Apache-2.0"
			(at 284.548 248.428 0)
			(layer "B.Fab")
			(hide yes)
			(effects
				(font
					(size 1 1)
					(thickness 0.15)
				)
				(justify mirror)
			)
		)
		(property "MPN" "CR0402-FX-4702GLF"
			(at 284.548 248.428 0)
			(layer "B.Fab")
			(hide yes)
			(effects
				(font
					(size 1 1)
					(thickness 0.15)
				)
				(justify mirror)
			)
		)
		(property "Manufacturer" "Bourns"
			(at 284.548 248.428 0)
			(layer "B.Fab")
			(hide yes)
			(effects
				(font
					(size 1 1)
					(thickness 0.15)
				)
				(justify mirror)
			)
		)
		(property "Tolerance" "1%"
			(at 284.548 248.428 0)
			(layer "B.Fab")
			(hide yes)
			(effects
				(font
					(size 1 1)
					(thickness 0.15)
				)
				(justify mirror)
			)
		)
		(property "Val" "47k"
			(at 284.548 248.428 0)
			(layer "B.Fab")
			(hide yes)
			(effects
				(font
					(size 1 1)
					(thickness 0.15)
				)
				(justify mirror)
			)
		)
		(sheetname "/Interfaces/")
		(sheetfile "interfaces.kicad_sch")
		(attr smd)
		(fp_rect
			(start -0.925 0.47)
			(end 0.925 -0.47)
			(stroke
				(width 0.05)
				(type default)
			)
			(fill no)
			(layer "B.CrtYd")
		)
		(fp_rect
			(start -0.5 0.25)
			(end 0.5 -0.25)
			(stroke
				(width 0.15)
				(type solid)
			)
			(fill no)
			(layer "B.Fab")
		)
		(pad "1" smd roundrect
			(at -0.48 0 180)
			(size 0.59 0.64)
			(layers "B.Cu" "B.Mask" "B.Paste")
			(roundrect_rratio 0.25)
			(net 2 "VCC3V3")
			(pintype "passive")
		)
		(pad "2" smd roundrect
			(at 0.48 0 180)
			(size 0.59 0.64)
			(layers "B.Cu" "B.Mask" "B.Paste")
			(roundrect_rratio 0.25)
			(net 321 "MMC_DAT0")
			(pintype "passive")
		)
	)
)
